# S9S_MB_2U (Grand Teton) — schematic netlist excerpt (pin names and nets, part order shuffled) for the footprints in the layout excerpt that follows; sources: Cadence DE-HDL packaged netlist, KiCad conversion of 03242023_DA0F0TMBIJ0_F0T_Motherboard_J_brd_V01_OCP.brd

R4892  Q_RES  49.9 1% EMPTY  pkg 0402LF  page 305 : A = P12V_HSC_TEMP_R ; B = P12V_HSC_TEMP_D+
PC633  Q_CAP  2.2UF 10V 10% X6S  pkg C0402  page 279 : A = PVCCD_HV_CPU0_VDD1 ; B = GND

(kicad_pcb
	(version 20260206)
	(generator "pcbnew")
	(generator_version "10.0")
	(general
		(thickness 1.6)
		(legacy_teardrops no)
	)
	(paper "A4")
	(title_block
		(title "03242023_DA0F0TMBIJ0_F0T_Motherboard_J_brd_V01_OCP.brd")
		(comment 1 "Grand Teton / footprints 3741-3742 of 6105")
	)
	(layers
		(0 "F.Cu" signal "TOP")
		(4 "In1.Cu" signal "GND")
		(6 "In2.Cu" signal "IN1")
		(8 "In3.Cu" signal "GND1")
		(10 "In4.Cu" signal "IN2")
		(12 "In5.Cu" signal "GND2")
		(14 "In6.Cu" signal "IN3")
		(16 "In7.Cu" signal "GND3")
		(18 "In8.Cu" signal "VCC")
		(20 "In9.Cu" signal "VCC1")
		(22 "In10.Cu" signal "GND4")
		(24 "In11.Cu" signal "IN4")
		(26 "In12.Cu" signal "GND5")
		(28 "In13.Cu" signal "IN5")
		(30 "In14.Cu" signal "GND6")
		(32 "In15.Cu" signal "IN6")
		(34 "In16.Cu" signal "GND7")
		(2 "B.Cu" signal "BOTTOM")
		(9 "F.Adhes" user "F.Adhesive")
		(11 "B.Adhes" user "B.Adhesive")
		(13 "F.Paste" user "Package Geometry/Pastemask Top")
		(15 "B.Paste" user "Package Geometry/Pastemask Bottom")
		(5 "F.SilkS" user "Ref Des/Silkscreen Top")
		(7 "B.SilkS" user "Ref Des/Silkscreen Bottom")
		(1 "F.Mask" user "Board Geometry/Soldermask Top")
		(3 "B.Mask" user "Board Geometry/Soldermask Bottom")
		(17 "Dwgs.User" user "User.Drawings")
		(19 "Cmts.User" user "User.Comments")
		(21 "Eco1.User" user "User.Eco1")
		(23 "Eco2.User" user "User.Eco2")
		(25 "Edge.Cuts" user "Board Geometry/Outline")
		(27 "Margin" user)
		(31 "F.CrtYd" user "Package Geometry/Place Bound Top")
		(29 "B.CrtYd" user "Package Geometry/Place Bound Bottom")
		(35 "F.Fab" user "Ref Des/Assembly Top")
		(33 "B.Fab" user "Ref Des/Assembly Bottom")
	)
	(footprint ""
		(layer "F.Cu")
		(at 284.63494 -409.52928)
		(property "Reference" "R4892"
			(at 0 0 0)
			(layer "F.SilkS")
			(hide yes)
			(effects
				(font
					(size 1.27 1.27)
				)
			)
		)
		(property "Value" ""
			(at 0 0 0)
			(layer "F.Fab")
			(effects
				(font
					(size 1.27 1.27)
				)
			)
		)
		(duplicate_pad_numbers_are_jumpers no)
		(fp_line
			(start -0.7874 -0.4064)
			(end 0.7874 -0.4064)
			(stroke
				(width 0.1524)
				(type default)
			)
			(layer "F.SilkS")
		)
		(fp_line
			(start -0.7874 0.4064)
			(end -0.7874 -0.4064)
			(stroke
				(width 0.1524)
				(type default)
			)
			(layer "F.SilkS")
		)
		(fp_line
			(start 0.7874 -0.4064)
			(end 0.7874 0.4064)
			(stroke
				(width 0.1524)
				(type default)
			)
			(layer "F.SilkS")
		)
		(fp_line
			(start 0.7874 0.4064)
			(end -0.7874 0.4064)
			(stroke
				(width 0.1524)
				(type default)
			)
			(layer "F.SilkS")
		)
		(fp_line
			(start -0.67945 -0.305054)
			(end -0.12065 -0.305054)
			(stroke
				(width 0.1)
				(type default)
			)
			(layer "F.Fab")
		)
		(fp_line
			(start -0.67945 0.3048)
			(end -0.67945 -0.305054)
			(stroke
				(width 0.1)
				(type default)
			)
			(layer "F.Fab")
		)
		(fp_line
			(start -0.12065 -0.305054)
			(end -0.12065 -0.2794)
			(stroke
				(width 0.1)
				(type default)
			)
			(layer "F.Fab")
		)
		(fp_line
			(start -0.12065 -0.2794)
			(end 0.12065 -0.2794)
			(stroke
				(width 0.1)
				(type default)
			)
			(layer "F.Fab")
		)
		(fp_line
			(start -0.12065 0.2794)
			(end -0.12065 0.3048)
			(stroke
				(width 0.1)
				(type default)
			)
			(layer "F.Fab")
		)
		(fp_line
			(start -0.12065 0.3048)
			(end -0.67945 0.3048)
			(stroke
				(width 0.1)
				(type default)
			)
			(layer "F.Fab")
		)
		(fp_line
			(start 0.120396 0.2794)
			(end -0.12065 0.2794)
			(stroke
				(width 0.1)
				(type default)
			)
			(layer "F.Fab")
		)
		(fp_line
			(start 0.120396 0.3048)
			(end 0.120396 0.2794)
			(stroke
				(width 0.1)
				(type default)
			)
			(layer "F.Fab")
		)
		(fp_line
			(start 0.12065 -0.3048)
			(end 0.67945 -0.3048)
			(stroke
				(width 0.1)
				(type default)
			)
			(layer "F.Fab")
		)
		(fp_line
			(start 0.12065 -0.2794)
			(end 0.12065 -0.3048)
			(stroke
				(width 0.1)
				(type default)
			)
			(layer "F.Fab")
		)
		(fp_line
			(start 0.67945 -0.3048)
			(end 0.67945 0.3048)
			(stroke
				(width 0.1)
				(type default)
			)
			(layer "F.Fab")
		)
		(fp_line
			(start 0.67945 0.3048)
			(end 0.120396 0.3048)
			(stroke
				(width 0.1)
				(type default)
			)
			(layer "F.Fab")
		)
		(pad "1" smd circle
			(at -0.40005 0)
			(size 0 0)
			(layers "F.Cu" "F.Mask" "F.Paste")
			(net "P12V_HSC_TEMP_R")
		)
		(pad "2" smd circle
			(at 0.40005 0)
			(size 0 0)
			(layers "F.Cu" "F.Mask" "F.Paste")
			(net "P12V_HSC_TEMP_D+")
		)
	)
	(footprint ""
		(layer "F.Cu")
		(at 418.485828 -165.760654)
		(property "Reference" "PC633"
			(at 0 0 0)
			(layer "F.SilkS")
			(hide yes)
			(effects
				(font
					(size 1.27 1.27)
				)
			)
		)
		(property "Value" ""
			(at 0 0 0)
			(layer "F.Fab")
			(effects
				(font
					(size 1.27 1.27)
				)
			)
		)
		(duplicate_pad_numbers_are_jumpers no)
		(fp_line
			(start -0.7874 -0.4064)
			(end 0.7874 -0.4064)
			(stroke
				(width 0.1524)
				(type default)
			)
			(layer "F.SilkS")
		)
		(fp_line
			(start -0.7874 0.4064)
			(end -0.7874 -0.4064)
			(stroke
				(width 0.1524)
				(type default)
			)
			(layer "F.SilkS")
		)
		(fp_line
			(start 0.7874 -0.4064)
			(end 0.7874 0.4064)
			(stroke
				(width 0.1524)
				(type default)
			)
			(layer "F.SilkS")
		)
		(fp_line
			(start 0.7874 0.4064)
			(end -0.7874 0.4064)
			(stroke
				(width 0.1524)
				(type default)
			)
			(layer "F.SilkS")
		)
		(fp_line
			(start -0.67945 -0.305054)
			(end -0.12065 -0.305054)
			(stroke
				(width 0.1)
				(type default)
			)
			(layer "F.Fab")
		)
		(fp_line
			(start -0.67945 0.3048)
			(end -0.67945 -0.305054)
			(stroke
				(width 0.1)
				(type default)
			)
			(layer "F.Fab")
		)
		(fp_line
			(start -0.12065 -0.305054)
			(end -0.12065 -0.2794)
			(stroke
				(width 0.1)
				(type default)
			)
			(layer "F.Fab")
		)
		(fp_line
			(start -0.12065 -0.2794)
			(end 0.12065 -0.2794)
			(stroke
				(width 0.1)
				(type default)
			)
			(layer "F.Fab")
		)
		(fp_line
			(start -0.12065 0.2794)
			(end -0.12065 0.3048)
			(stroke
				(width 0.1)
				(type default)
			)
			(layer "F.Fab")
		)
		(fp_line
			(start -0.12065 0.3048)
			(end -0.67945 0.3048)
			(stroke
				(width 0.1)
				(type default)
			)
			(layer "F.Fab")
		)
		(fp_line
			(start 0.120396 0.2794)
			(end -0.12065 0.2794)
			(stroke
				(width 0.1)
				(type default)
			)
			(layer "F.Fab")
		)
		(fp_line
			(start 0.120396 0.3048)
			(end 0.120396 0.2794)
			(stroke
				(width 0.1)
				(type default)
			)
			(layer "F.Fab")
		)
		(fp_line
			(start 0.12065 -0.3048)
			(end 0.67945 -0.3048)
			(stroke
				(width 0.1)
				(type default)
			)
			(layer "F.Fab")
		)
		(fp_line
			(start 0.12065 -0.2794)
			(end 0.12065 -0.3048)
			(stroke
				(width 0.1)
				(type default)
			)
			(layer "F.Fab")
		)
		(fp_line
			(start 0.67945 -0.3048)
			(end 0.67945 0.3048)
			(stroke
				(width 0.1)
				(type default)
			)
			(layer "F.Fab")
		)
		(fp_line
			(start 0.67945 0.3048)
			(end 0.120396 0.3048)
			(stroke
				(width 0.1)
				(type default)
			)
			(layer "F.Fab")
		)
		(pad "1" smd circle
			(at -0.40005 0)
			(size 0 0)
			(layers "F.Cu" "F.Mask" "F.Paste")
			(net "PVCCD_HV_CPU0_VDD1")
		)
		(pad "2" smd circle
			(at 0.40005 0)
			(size 0 0)
			(layers "F.Cu" "F.Mask" "F.Paste")
			(net "GND")
		)
	)
)
